(kicad_pcb
	(version 20240108)
	(generator "pcbnew")
	(generator_version "8.0")
	(general
		(thickness 1.586)
		(legacy_teardrops no)
	)
	(paper "A4")
	(title_block
		(title "GMSL Serializer")
		(date "2024-11-27")
		(rev "1.1.1")
		(company "Antmicro Ltd")
		(comment 1 "www.antmicro.com")
		(comment 9 "footprints 105-109 of 117")
	)
	(layers
		(0 "F.Cu" signal)
		(1 "In1.Cu" power)
		(2 "In2.Cu" power)
		(31 "B.Cu" signal)
		(32 "B.Adhes" user "B.Adhesive")
		(33 "F.Adhes" user "F.Adhesive")
		(34 "B.Paste" user)
		(35 "F.Paste" user)
		(36 "B.SilkS" user "B.Silkscreen")
		(37 "F.SilkS" user "F.Silkscreen")
		(38 "B.Mask" user)
		(39 "F.Mask" user)
		(40 "Dwgs.User" user "User.Drawings")
		(41 "Cmts.User" user "User.Comments")
		(42 "Eco1.User" user "User.Eco1")
		(43 "Eco2.User" user "User.Eco2")
		(44 "Edge.Cuts" user)
		(45 "Margin" user)
		(46 "B.CrtYd" user "B.Courtyard")
		(47 "F.CrtYd" user "F.Courtyard")
		(48 "B.Fab" user)
		(49 "F.Fab" user)
	)
	(footprint "antmicro-footprints:C_0402_1005Metric"
		(layer "F.Cu")
		(at 145.1 85.75 -90)
		(descr "Capacitor SMD 0402")
		(tags "capacitor SMD 0402")
		(property "Reference" "C35"
			(at 0.85 -0.95 90)
			(layer "F.SilkS")
			(effects
				(font
					(size 0.7 0.7)
					(thickness 0.15)
				)
				(justify right top)
			)
		)
		(property "Value" "C_22u_0402"
			(at -1.022927 2.155213 90)
			(layer "F.Fab")
			(effects
				(font
					(size 0.7 0.7)
					(thickness 0.15)
				)
				(justify right top)
			)
		)
		(property "Footprint" "antmicro-footprints:C_0402_1005Metric"
			(at 0 0 90)
			(layer "F.Fab")
			(hide yes)
			(effects
				(font
					(size 1.27 1.27)
					(thickness 0.15)
				)
			)
		)
		(property "Datasheet" "https://www.murata.com/products/productdetail?partno=GRM158R60J226ME01%23"
			(at 0 0 90)
			(layer "F.Fab")
			(hide yes)
			(effects
				(font
					(size 1.27 1.27)
					(thickness 0.15)
				)
			)
		)
		(property "MPN" "GRM158R60J226ME01D"
			(at 0 0 -90)
			(unlocked yes)
			(layer "F.Fab")
			(hide yes)
			(effects
				(font
					(size 1 1)
					(thickness 0.15)
				)
			)
		)
		(property "Manufacturer" "Murata"
			(at 0 0 -90)
			(unlocked yes)
			(layer "F.Fab")
			(hide yes)
			(effects
				(font
					(size 1 1)
					(thickness 0.15)
				)
			)
		)
		(property "License" "Apache-2.0"
			(at 0 0 -90)
			(unlocked yes)
			(layer "F.Fab")
			(hide yes)
			(effects
				(font
					(size 1 1)
					(thickness 0.15)
				)
			)
		)
		(property "Author" "Antmicro"
			(at 0 0 -90)
			(unlocked yes)
			(layer "F.Fab")
			(hide yes)
			(effects
				(font
					(size 1 1)
					(thickness 0.15)
				)
			)
		)
		(property "Val" "22u"
			(at 0 0 -90)
			(unlocked yes)
			(layer "F.Fab")
			(hide yes)
			(effects
				(font
					(size 1 1)
					(thickness 0.15)
				)
			)
		)
		(property "Voltage" ""
			(at 0 0 -90)
			(unlocked yes)
			(layer "F.Fab")
			(hide yes)
			(effects
				(font
					(size 1 1)
					(thickness 0.15)
				)
			)
		)
		(property "Dielectric" ""
			(at 0 0 -90)
			(unlocked yes)
			(layer "F.Fab")
			(hide yes)
			(effects
				(font
					(size 1 1)
					(thickness 0.15)
				)
			)
		)
		(sheetname "Supply")
		(sheetfile "supply.kicad_sch")
		(attr smd)
		(fp_rect
			(start -0.925 -0.47)
			(end 0.925 0.47)
			(stroke
				(width 0.05)
				(type default)
			)
			(fill none)
			(layer "F.CrtYd")
		)
		(fp_line
			(start -0.494 0.248)
			(end -0.494 -0.25)
			(stroke
				(width 0.15)
				(type solid)
			)
			(layer "F.Fab")
		)
		(fp_line
			(start 0.504 0.248)
			(end -0.494 0.248)
			(stroke
				(width 0.15)
				(type solid)
			)
			(layer "F.Fab")
		)
		(fp_line
			(start -0.494 -0.25)
			(end 0.504 -0.25)
			(stroke
				(width 0.15)
				(type solid)
			)
			(layer "F.Fab")
		)
		(fp_line
			(start 0.504 -0.25)
			(end 0.504 0.248)
			(stroke
				(width 0.15)
				(type solid)
			)
			(layer "F.Fab")
		)
		(fp_text user "License: Apache-2.0"
			(at -0.939 5.799 90)
			(layer "F.Fab")
			(hide yes)
			(effects
				(font
					(size 0.7 0.7)
					(thickness 0.15)
				)
				(justify right top)
			)
		)
		(fp_text user "${REFERENCE}"
			(at -0.939 4.599 90)
			(layer "F.Fab")
			(hide yes)
			(effects
				(font
					(size 0.7 0.7)
					(thickness 0.15)
				)
				(justify right top)
			)
		)
		(fp_text user "Author: Antmicro"
			(at -0.939 3.399 90)
			(layer "F.Fab")
			(hide yes)
			(effects
				(font
					(size 0.7 0.7)
					(thickness 0.15)
				)
				(justify right top)
			)
		)
		(pad "1" smd roundrect
			(at -0.48 0 270)
			(size 0.59 0.64)
			(layers "F.Cu" "F.Paste" "F.Mask")
			(roundrect_rratio 0.25)
			(net 1 "GND")
			(pintype "passive")
		)
		(pad "2" smd roundrect
			(at 0.48 0 270)
			(size 0.59 0.64)
			(layers "F.Cu" "F.Paste" "F.Mask")
			(roundrect_rratio 0.25)
			(net 94 "/Supply/OUT_3V3")
			(pintype "passive")
		)
	)
	(footprint "antmicro-footprints:C_0402_1005Metric"
		(layer "F.Cu")
		(at 152.69 103.33 -45)
		(descr "Capacitor SMD 0402")
		(tags "capacitor SMD 0402")
		(property "Reference" "C16"
			(at 0.92631 0.374767 -45)
			(unlocked yes)
			(layer "F.SilkS")
			(effects
				(font
					(size 0.7 0.7)
					(thickness 0.15)
				)
				(justify left bottom)
			)
		)
		(property "Value" "C_33p_0402"
			(at -1.022927 2.155213 135)
			(layer "F.Fab")
			(effects
				(font
					(size 0.7 0.7)
					(thickness 0.15)
				)
				(justify right bottom)
			)
		)
		(property "Footprint" "antmicro-footprints:C_0402_1005Metric"
			(at 0 0 -45)
			(layer "F.Fab")
			(hide yes)
			(effects
				(font
					(size 1.27 1.27)
					(thickness 0.15)
				)
			)
		)
		(property "Datasheet" "https://spicat.kyocera-avx.com/product/mlcc/chartview/04025A330FAT2A/"
			(at 0 0 -45)
			(layer "F.Fab")
			(hide yes)
			(effects
				(font
					(size 1.27 1.27)
					(thickness 0.15)
				)
			)
		)
		(property "Author" "Antmicro"
			(at -28.343478 138.23279 0)
			(layer "F.Fab")
			(hide yes)
			(effects
				(font
					(size 1 1)
					(thickness 0.15)
				)
			)
		)
		(property "Dielectric" ""
			(at -28.343478 138.23279 0)
			(layer "F.Fab")
			(hide yes)
			(effects
				(font
					(size 1 1)
					(thickness 0.15)
				)
			)
		)
		(property "License" "Apache-2.0"
			(at -28.343478 138.23279 0)
			(layer "F.Fab")
			(hide yes)
			(effects
				(font
					(size 1 1)
					(thickness 0.15)
				)
			)
		)
		(property "MPN" "04025A330FAT2A"
			(at -28.343478 138.23279 0)
			(layer "F.Fab")
			(hide yes)
			(effects
				(font
					(size 1 1)
					(thickness 0.15)
				)
			)
		)
		(property "Manufacturer" "KYOCERA AVX"
			(at -28.343478 138.23279 0)
			(layer "F.Fab")
			(hide yes)
			(effects
				(font
					(size 1 1)
					(thickness 0.15)
				)
			)
		)
		(property "Val" "33p"
			(at -28.343478 138.23279 0)
			(layer "F.Fab")
			(hide yes)
			(effects
				(font
					(size 1 1)
					(thickness 0.15)
				)
			)
		)
		(property "Voltage" ""
			(at -28.343478 138.23279 0)
			(layer "F.Fab")
			(hide yes)
			(effects
				(font
					(size 1 1)
					(thickness 0.15)
				)
			)
		)
		(sheetname "Serializer")
		(sheetfile "serializer.kicad_sch")
		(attr smd)
		(fp_poly
			(pts
				(xy -0.925 -0.47) (xy 0.925 -0.47) (xy 0.925 0.47) (xy -0.925 0.47)
			)
			(stroke
				(width 0.05)
				(type default)
			)
			(fill none)
			(layer "F.CrtYd")
		)
		(fp_line
			(start -0.494 0.248)
			(end -0.494 -0.25)
			(stroke
				(width 0.15)
				(type solid)
			)
			(layer "F.Fab")
		)
		(fp_line
			(start -0.494 -0.25)
			(end 0.504 -0.25)
			(stroke
				(width 0.15)
				(type solid)
			)
			(layer "F.Fab")
		)
		(fp_line
			(start 0.504 0.248)
			(end -0.494 0.248)
			(stroke
				(width 0.15)
				(type solid)
			)
			(layer "F.Fab")
		)
		(fp_line
			(start 0.504 -0.25)
			(end 0.504 0.248)
			(stroke
				(width 0.15)
				(type solid)
			)
			(layer "F.Fab")
		)
		(fp_text user "License: Apache-2.0"
			(at -0.939 5.799 135)
			(layer "F.Fab")
			(hide yes)
			(effects
				(font
					(size 0.7 0.7)
					(thickness 0.15)
				)
				(justify right bottom)
			)
		)
		(fp_text user "${REFERENCE}"
			(at -0.939 4.599 135)
			(layer "F.Fab")
			(hide yes)
			(effects
				(font
					(size 0.7 0.7)
					(thickness 0.15)
				)
				(justify right bottom)
			)
		)
		(fp_text user "Author: Antmicro"
			(at -0.939 3.399 135)
			(layer "F.Fab")
			(hide yes)
			(effects
				(font
					(size 0.7 0.7)
					(thickness 0.15)
				)
				(justify right bottom)
			)
		)
		(pad "1" smd roundrect
			(at -0.48 0 315)
			(size 0.59 0.64)
			(layers "F.Cu" "F.Paste" "F.Mask")
			(roundrect_rratio 0.25)
			(net 1 "GND")
			(pintype "passive")
		)
		(pad "2" smd roundrect
			(at 0.48 0 315)
			(size 0.59 0.64)
			(layers "F.Cu" "F.Paste" "F.Mask")
			(roundrect_rratio 0.25)
			(net 13 "/Serializer/X1")
			(pintype "passive")
		)
	)
	(footprint "antmicro-footprints:R_0402_1005Metric"
		(layer "F.Cu")
		(at 152.069483 99.847484 -135)
		(descr "Resistor SMD 0402")
		(tags "resistor SMD 0402")
		(property "Reference" "R23"
			(at -2.224489 -0.137712 45)
			(layer "F.SilkS")
			(effects
				(font
					(size 0.7 0.7)
					(thickness 0.15)
				)
				(justify left bottom)
			)
		)
		(property "Value" "R_402R_0402"
			(at -1.011843 1.772046 45)
			(layer "F.Fab")
			(effects
				(font
					(size 0.7 0.7)
					(thickness 0.15)
				)
				(justify right bottom)
			)
		)
		(property "Footprint" "antmicro-footprints:R_0402_1005Metric"
			(at 0 0 -135)
			(layer "F.Fab")
			(hide yes)
			(effects
				(font
					(size 1.27 1.27)
					(thickness 0.15)
				)
			)
		)
		(property "Datasheet" "https://www.mouser.com/datasheet/2/54/cr-1858361.pdf"
			(at 0 0 -135)
			(layer "F.Fab")
			(hide yes)
			(effects
				(font
					(size 1.27 1.27)
					(thickness 0.15)
				)
			)
		)
		(property "Author" "Antmicro"
			(at 188.996013 277.97968 0)
			(layer "F.Fab")
			(hide yes)
			(effects
				(font
					(size 1 1)
					(thickness 0.15)
				)
			)
		)
		(property "License" "Apache-2.0"
			(at 188.996013 277.97968 0)
			(layer "F.Fab")
			(hide yes)
			(effects
				(font
					(size 1 1)
					(thickness 0.15)
				)
			)
		)
		(property "MPN" "CR0402-FX-4020GLF"
			(at 188.996013 277.97968 0)
			(layer "F.Fab")
			(hide yes)
			(effects
				(font
					(size 1 1)
					(thickness 0.15)
				)
			)
		)
		(property "Manufacturer" "Bourns"
			(at 188.996013 277.97968 0)
			(layer "F.Fab")
			(hide yes)
			(effects
				(font
					(size 1 1)
					(thickness 0.15)
				)
			)
		)
		(property "Tolerance" "1%"
			(at 188.996013 277.97968 0)
			(layer "F.Fab")
			(hide yes)
			(effects
				(font
					(size 1 1)
					(thickness 0.15)
				)
			)
		)
		(property "Val" "402R"
			(at 188.996013 277.97968 0)
			(layer "F.Fab")
			(hide yes)
			(effects
				(font
					(size 1 1)
					(thickness 0.15)
				)
			)
		)
		(sheetname "Serializer")
		(sheetfile "serializer.kicad_sch")
		(attr smd)
		(fp_poly
			(pts
				(xy -0.925 -0.47) (xy 0.925 -0.47) (xy 0.925 0.47) (xy -0.925 0.47)
			)
			(stroke
				(width 0.05)
				(type default)
			)
			(fill none)
			(layer "F.CrtYd")
		)
		(fp_poly
			(pts
				(xy -0.5 -0.25) (xy 0.5 -0.25) (xy 0.5 0.25) (xy -0.5 0.25)
			)
			(stroke
				(width 0.15)
				(type solid)
			)
			(fill none)
			(layer "F.Fab")
		)
		(fp_text user "${REFERENCE}"
			(at -0.95 3.168 45)
			(layer "F.Fab")
			(hide yes)
			(effects
				(font
					(size 0.7 0.7)
					(thickness 0.15)
				)
				(justify right bottom)
			)
		)
		(fp_text user "License: Apache-2.0"
			(at -0.949999 5.169 45)
			(layer "F.Fab")
			(hide yes)
			(effects
				(font
					(size 0.7 0.7)
					(thickness 0.15)
				)
				(justify right bottom)
			)
		)
		(fp_text user "Author: Antmicro"
			(at -0.95 4.169 45)
			(layer "F.Fab")
			(hide yes)
			(effects
				(font
					(size 0.7 0.7)
					(thickness 0.15)
				)
				(justify right bottom)
			)
		)
		(pad "1" smd roundrect
			(at -0.48 0 225)
			(size 0.59 0.64)
			(layers "F.Cu" "F.Paste" "F.Mask")
			(roundrect_rratio 0.25)
			(net 1 "GND")
			(pintype "passive")
		)
		(pad "2" smd roundrect
			(at 0.48 0 225)
			(size 0.59 0.64)
			(layers "F.Cu" "F.Paste" "F.Mask")
			(roundrect_rratio 0.25)
			(net 76 "Net-(U6-XRES)")
			(pintype "passive")
		)
	)
	(footprint "antmicro-footprints:R_0402_1005Metric"
		(layer "F.Cu")
		(at 135.4 109.884)
		(descr "Resistor SMD 0402")
		(tags "resistor SMD 0402")
		(property "Reference" "R30"
			(at 0.9 0.341 0)
			(layer "F.SilkS")
			(effects
				(font
					(size 0.7 0.7)
					(thickness 0.15)
				)
				(justify left bottom)
			)
		)
		(property "Value" "R_0R_0402"
			(at -1.011843 1.772047 0)
			(layer "F.Fab")
			(effects
				(font
					(size 0.7 0.7)
					(thickness 0.15)
				)
				(justify left bottom)
			)
		)
		(property "Footprint" "antmicro-footprints:R_0402_1005Metric"
			(at 0 0 0)
			(layer "F.Fab")
			(hide yes)
			(effects
				(font
					(size 1.27 1.27)
					(thickness 0.15)
				)
			)
		)
		(property "Datasheet" "https://industrial.panasonic.com/cdbs/www-data/pdf/RDA0000/AOA0000C301.pdf"
			(at 0 0 0)
			(layer "F.Fab")
			(hide yes)
			(effects
				(font
					(size 1.27 1.27)
					(thickness 0.15)
				)
			)
		)
		(property "Author" "Antmicro"
			(at 0 0 0)
			(layer "F.Fab")
			(hide yes)
			(effects
				(font
					(size 1 1)
					(thickness 0.15)
				)
			)
		)
		(property "Current" "1A"
			(at 0 0 0)
			(layer "F.Fab")
			(hide yes)
			(effects
				(font
					(size 1 1)
					(thickness 0.15)
				)
			)
		)
		(property "License" "Apache-2.0"
			(at 0 0 0)
			(layer "F.Fab")
			(hide yes)
			(effects
				(font
					(size 1 1)
					(thickness 0.15)
				)
			)
		)
		(property "MPN" "ERJ2GE0R00X"
			(at 0 0 0)
			(layer "F.Fab")
			(hide yes)
			(effects
				(font
					(size 1 1)
					(thickness 0.15)
				)
			)
		)
		(property "Manufacturer" "Panasonic"
			(at 0 0 0)
			(layer "F.Fab")
			(hide yes)
			(effects
				(font
					(size 1 1)
					(thickness 0.15)
				)
			)
		)
		(property "Tolerance" ""
			(at 0 0 0)
			(layer "F.Fab")
			(hide yes)
			(effects
				(font
					(size 1 1)
					(thickness 0.15)
				)
			)
		)
		(property "Val" "0R"
			(at 0 0 0)
			(layer "F.Fab")
			(hide yes)
			(effects
				(font
					(size 1 1)
					(thickness 0.15)
				)
			)
		)
		(sheetname "Serializer")
		(sheetfile "serializer.kicad_sch")
		(attr smd exclude_from_bom dnp)
		(fp_rect
			(start -0.925 -0.47)
			(end 0.925 0.47)
			(stroke
				(width 0.05)
				(type default)
			)
			(fill none)
			(layer "F.CrtYd")
		)
		(fp_rect
			(start -0.5 -0.25)
			(end 0.5 0.25)
			(stroke
				(width 0.15)
				(type solid)
			)
			(fill none)
			(layer "F.Fab")
		)
		(fp_text user "Author: Antmicro"
			(at -0.95 4.169 0)
			(layer "F.Fab")
			(hide yes)
			(effects
				(font
					(size 0.7 0.7)
					(thickness 0.15)
				)
				(justify left bottom)
			)
		)
		(fp_text user "${REFERENCE}"
			(at -0.95 3.168 0)
			(layer "F.Fab")
			(hide yes)
			(effects
				(font
					(size 0.7 0.7)
					(thickness 0.15)
				)
				(justify left bottom)
			)
		)
		(fp_text user "License: Apache-2.0"
			(at -0.95 5.169 0)
			(layer "F.Fab")
			(hide yes)
			(effects
				(font
					(size 0.7 0.7)
					(thickness 0.15)
				)
				(justify left bottom)
			)
		)
		(pad "1" smd roundrect
			(at -0.48 0)
			(size 0.59 0.64)
			(layers "F.Cu" "F.Paste" "F.Mask")
			(roundrect_rratio 0.25)
			(net 88 "/CSI Connector/I2C.SDA")
			(pintype "passive")
		)
		(pad "2" smd roundrect
			(at 0.48 0)
			(size 0.59 0.64)
			(layers "F.Cu" "F.Paste" "F.Mask")
			(roundrect_rratio 0.25)
			(net 78 "Net-(U6-MFP7)")
			(pintype "passive")
		)
	)
	(footprint "antmicro-footprints:TP_SMD_1.5mm"
		(layer "F.Cu")
		(at 153.25 118)
		(property "Reference" "TP6"
			(at -0.8 -1 0)
			(layer "F.SilkS")
			(hide yes)
			(effects
				(font
					(size 0.7 0.7)
					(thickness 0.15)
				)
				(justify left bottom)
			)
		)
		(property "Value" "TP_1.5mm_SMD"
			(at 0 1.7 0)
			(layer "F.Fab")
			(effects
				(font
					(size 0.7 0.7)
					(thickness 0.15)
				)
				(justify left bottom)
			)
		)
		(property "Footprint" "antmicro-footprints:TP_SMD_1.5mm"
			(at 0 0 0)
			(layer "F.Fab")
			(hide yes)
			(effects
				(font
					(size 1.27 1.27)
					(thickness 0.15)
				)
			)
		)
		(property "Author" "Antmicro"
			(at 0 0 0)
			(layer "F.Fab")
			(hide yes)
			(effects
				(font
					(size 1 1)
					(thickness 0.15)
				)
			)
		)
		(property "License" "Apache-2.0"
			(at 0 0 0)
			(layer "F.Fab")
			(hide yes)
			(effects
				(font
					(size 1 1)
					(thickness 0.15)
				)
			)
		)
		(property "MPN" ""
			(at 0 0 0)
			(layer "F.Fab")
			(hide yes)
			(effects
				(font
					(size 1 1)
					(thickness 0.15)
				)
			)
		)
		(property "Manufacturer" ""
			(at 0 0 0)
			(layer "F.Fab")
			(hide yes)
			(effects
				(font
					(size 1 1)
					(thickness 0.15)
				)
			)
		)
		(sheetname "Serializer")
		(sheetfile "serializer.kicad_sch")
		(attr exclude_from_pos_files exclude_from_bom)
		(fp_circle
			(center 0 0)
			(end 0.85 0)
			(stroke
				(width 0.05)
				(type default)
			)
			(fill none)
			(layer "F.CrtYd")
		)
		(fp_text user "License: Apache-2.0"
			(at -0.7 5.301 0)
			(layer "F.Fab")
			(hide yes)
			(effects
				(font
					(size 0.7 0.7)
					(thickness 0.15)
				)
				(justify left bottom)
			)
		)
		(fp_text user "Author: Antmicro"
			(at -0.7 4.101 0)
			(layer "F.Fab")
			(hide yes)
			(effects
				(font
					(size 0.7 0.7)
					(thickness 0.15)
				)
				(justify left bottom)
			)
		)
		(fp_text user "${REFERENCE}"
			(at -0.7 2.9 0)
			(layer "F.Fab")
			(hide yes)
			(effects
				(font
					(size 0.7 0.7)
					(thickness 0.15)
				)
				(justify left bottom)
			)
		)
		(pad "1" smd circle
			(at 0 0 270)
			(size 1.5 1.5)
			(layers "F.Cu" "F.Mask")
			(net 83 "Net-(U6-MFP0)")
			(pinfunction "1")
			(pintype "passive")
		)
	)
)
